# SCM (Grand Teton) — schematic netlist excerpt (pin names and nets, part order shuffled) for the footprints in the layout excerpt that follows; sources: Cadence DE-HDL packaged netlist, KiCad conversion of 12092022_DA0F0TMDCD0_F0T_Management_Board_D_brd_V3_OCP.brd

C143  Q_CAP  10UF 6.3V 20% X6S  pkg C0402  page 46 : A = P3V3_AUX ; B = GND
R838  Q_RES  0 5% CHIP  pkg 0402LF  page 10 : A = HDD_LED_N ; B = FM_HDD_LED_N

(kicad_pcb
	(version 20260206)
	(generator "pcbnew")
	(generator_version "10.0")
	(general
		(thickness 1.6)
		(legacy_teardrops no)
	)
	(paper "A4")
	(title_block
		(title "12092022_DA0F0TMDCD0_F0T_Management_Board_D_brd_V3_OCP.brd")
		(comment 1 "Grand Teton / footprints 63-64 of 1440")
	)
	(layers
		(0 "F.Cu" signal "TOP")
		(4 "In1.Cu" signal "GND")
		(6 "In2.Cu" signal "IN1")
		(8 "In3.Cu" signal "GND1")
		(10 "In4.Cu" signal "IN2")
		(12 "In5.Cu" signal "VCC")
		(14 "In6.Cu" signal "VCC1")
		(16 "In7.Cu" signal "IN3")
		(18 "In8.Cu" signal "GND2")
		(20 "In9.Cu" signal "IN4")
		(22 "In10.Cu" signal "GND3")
		(2 "B.Cu" signal "BOTTOM")
		(9 "F.Adhes" user "F.Adhesive")
		(11 "B.Adhes" user "B.Adhesive")
		(13 "F.Paste" user "Package Geometry/Pastemask Top")
		(15 "B.Paste" user "Package Geometry/Pastemask Bottom")
		(5 "F.SilkS" user "Ref Des/Silkscreen Top")
		(7 "B.SilkS" user "Ref Des/Silkscreen Bottom")
		(1 "F.Mask" user "Board Geometry/Soldermask Top")
		(3 "B.Mask" user "Board Geometry/Soldermask Bottom")
		(17 "Dwgs.User" user "User.Drawings")
		(19 "Cmts.User" user "User.Comments")
		(21 "Eco1.User" user "User.Eco1")
		(23 "Eco2.User" user "User.Eco2")
		(25 "Edge.Cuts" user "Board Geometry/Outline")
		(27 "Margin" user)
		(31 "F.CrtYd" user "Package Geometry/Place Bound Top")
		(29 "B.CrtYd" user "Package Geometry/Place Bound Bottom")
		(35 "F.Fab" user "Ref Des/Assembly Top")
		(33 "B.Fab" user "Ref Des/Assembly Bottom")
	)
	(footprint ""
		(layer "F.Cu")
		(at 11.3538 -109.347 90)
		(property "Reference" "R838"
			(at 0 0 90)
			(layer "F.SilkS")
			(hide yes)
			(effects
				(font
					(size 1.27 1.27)
				)
			)
		)
		(property "Value" ""
			(at 0 0 90)
			(layer "F.Fab")
			(effects
				(font
					(size 1.27 1.27)
				)
			)
		)
		(duplicate_pad_numbers_are_jumpers no)
		(fp_line
			(start 0.7874 -0.4064)
			(end 0.7874 0.4064)
			(stroke
				(width 0.1524)
				(type default)
			)
			(layer "F.SilkS")
		)
		(fp_line
			(start -0.7874 -0.4064)
			(end 0.7874 -0.4064)
			(stroke
				(width 0.1524)
				(type default)
			)
			(layer "F.SilkS")
		)
		(fp_line
			(start 0.7874 0.4064)
			(end -0.7874 0.4064)
			(stroke
				(width 0.1524)
				(type default)
			)
			(layer "F.SilkS")
		)
		(fp_line
			(start -0.7874 0.4064)
			(end -0.7874 -0.4064)
			(stroke
				(width 0.1524)
				(type default)
			)
			(layer "F.SilkS")
		)
		(fp_line
			(start -0.12065 -0.305054)
			(end -0.12065 -0.2794)
			(stroke
				(width 0.1)
				(type default)
			)
			(layer "F.Fab")
		)
		(fp_line
			(start -0.67945 -0.305054)
			(end -0.12065 -0.305054)
			(stroke
				(width 0.1)
				(type default)
			)
			(layer "F.Fab")
		)
		(fp_line
			(start 0.67945 -0.3048)
			(end 0.67945 0.3048)
			(stroke
				(width 0.1)
				(type default)
			)
			(layer "F.Fab")
		)
		(fp_line
			(start 0.12065 -0.3048)
			(end 0.67945 -0.3048)
			(stroke
				(width 0.1)
				(type default)
			)
			(layer "F.Fab")
		)
		(fp_line
			(start 0.12065 -0.2794)
			(end 0.12065 -0.3048)
			(stroke
				(width 0.1)
				(type default)
			)
			(layer "F.Fab")
		)
		(fp_line
			(start -0.12065 -0.2794)
			(end 0.12065 -0.2794)
			(stroke
				(width 0.1)
				(type default)
			)
			(layer "F.Fab")
		)
		(fp_line
			(start 0.120396 0.2794)
			(end -0.12065 0.2794)
			(stroke
				(width 0.1)
				(type default)
			)
			(layer "F.Fab")
		)
		(fp_line
			(start -0.12065 0.2794)
			(end -0.12065 0.3048)
			(stroke
				(width 0.1)
				(type default)
			)
			(layer "F.Fab")
		)
		(fp_line
			(start 0.67945 0.3048)
			(end 0.120396 0.3048)
			(stroke
				(width 0.1)
				(type default)
			)
			(layer "F.Fab")
		)
		(fp_line
			(start 0.120396 0.3048)
			(end 0.120396 0.2794)
			(stroke
				(width 0.1)
				(type default)
			)
			(layer "F.Fab")
		)
		(fp_line
			(start -0.12065 0.3048)
			(end -0.67945 0.3048)
			(stroke
				(width 0.1)
				(type default)
			)
			(layer "F.Fab")
		)
		(fp_line
			(start -0.67945 0.3048)
			(end -0.67945 -0.305054)
			(stroke
				(width 0.1)
				(type default)
			)
			(layer "F.Fab")
		)
		(pad "1" smd circle
			(at -0.40005 0 90)
			(size 0 0)
			(layers "F.Cu" "F.Mask" "F.Paste")
			(net "HDD_LED_N")
		)
		(pad "2" smd circle
			(at 0.40005 0 90)
			(size 0 0)
			(layers "F.Cu" "F.Mask" "F.Paste")
			(net "FM_HDD_LED_N")
		)
	)
	(footprint ""
		(layer "F.Cu")
		(at 74.09815 -91.061032 180)
		(property "Reference" "C143"
			(at 0 0 180)
			(layer "F.SilkS")
			(hide yes)
			(effects
				(font
					(size 1.27 1.27)
				)
			)
		)
		(property "Value" ""
			(at 0 0 180)
			(layer "F.Fab")
			(effects
				(font
					(size 1.27 1.27)
				)
			)
		)
		(duplicate_pad_numbers_are_jumpers no)
		(fp_line
			(start 0.7874 0.4064)
			(end -0.7874 0.4064)
			(stroke
				(width 0.1524)
				(type default)
			)
			(layer "F.SilkS")
		)
		(fp_line
			(start 0.7874 -0.4064)
			(end 0.7874 0.4064)
			(stroke
				(width 0.1524)
				(type default)
			)
			(layer "F.SilkS")
		)
		(fp_line
			(start -0.7874 0.4064)
			(end -0.7874 -0.4064)
			(stroke
				(width 0.1524)
				(type default)
			)
			(layer "F.SilkS")
		)
		(fp_line
			(start -0.7874 -0.4064)
			(end 0.7874 -0.4064)
			(stroke
				(width 0.1524)
				(type default)
			)
			(layer "F.SilkS")
		)
		(fp_line
			(start 0.67945 0.3048)
			(end 0.120396 0.3048)
			(stroke
				(width 0.1)
				(type default)
			)
			(layer "F.Fab")
		)
		(fp_line
			(start 0.67945 -0.3048)
			(end 0.67945 0.3048)
			(stroke
				(width 0.1)
				(type default)
			)
			(layer "F.Fab")
		)
		(fp_line
			(start 0.12065 -0.2794)
			(end 0.12065 -0.3048)
			(stroke
				(width 0.1)
				(type default)
			)
			(layer "F.Fab")
		)
		(fp_line
			(start 0.12065 -0.3048)
			(end 0.67945 -0.3048)
			(stroke
				(width 0.1)
				(type default)
			)
			(layer "F.Fab")
		)
		(fp_line
			(start 0.120396 0.3048)
			(end 0.120396 0.2794)
			(stroke
				(width 0.1)
				(type default)
			)
			(layer "F.Fab")
		)
		(fp_line
			(start 0.120396 0.2794)
			(end -0.12065 0.2794)
			(stroke
				(width 0.1)
				(type default)
			)
			(layer "F.Fab")
		)
		(fp_line
			(start -0.12065 0.3048)
			(end -0.67945 0.3048)
			(stroke
				(width 0.1)
				(type default)
			)
			(layer "F.Fab")
		)
		(fp_line
			(start -0.12065 0.2794)
			(end -0.12065 0.3048)
			(stroke
				(width 0.1)
				(type default)
			)
			(layer "F.Fab")
		)
		(fp_line
			(start -0.12065 -0.2794)
			(end 0.12065 -0.2794)
			(stroke
				(width 0.1)
				(type default)
			)
			(layer "F.Fab")
		)
		(fp_line
			(start -0.12065 -0.305054)
			(end -0.12065 -0.2794)
			(stroke
				(width 0.1)
				(type default)
			)
			(layer "F.Fab")
		)
		(fp_line
			(start -0.67945 0.3048)
			(end -0.67945 -0.305054)
			(stroke
				(width 0.1)
				(type default)
			)
			(layer "F.Fab")
		)
		(fp_line
			(start -0.67945 -0.305054)
			(end -0.12065 -0.305054)
			(stroke
				(width 0.1)
				(type default)
			)
			(layer "F.Fab")
		)
		(pad "1" smd circle
			(at -0.40005 0 180)
			(size 0 0)
			(layers "F.Cu" "F.Mask" "F.Paste")
			(net "P3V3_AUX")
		)
		(pad "2" smd circle
			(at 0.40005 0 180)
			(size 0 0)
			(layers "F.Cu" "F.Mask" "F.Paste")
			(net "GND")
		)
	)
)
